(kicad_pcb
	(version 20260206)
	(generator "pcbnew")
	(generator_version "10.0")
	(general
		(thickness 1.6)
		(legacy_teardrops no)
	)
	(paper "A4")
	(title_block
		(title "03242023_DA0F0TMBIJ0_F0T_Motherboard_J_brd_V01_OCP.brd")
		(comment 1 "Grand Teton / footprints 5961-5967 of 6105")
	)
	(layers
		(0 "F.Cu" signal "TOP")
		(4 "In1.Cu" signal "GND")
		(6 "In2.Cu" signal "IN1")
		(8 "In3.Cu" signal "GND1")
		(10 "In4.Cu" signal "IN2")
		(12 "In5.Cu" signal "GND2")
		(14 "In6.Cu" signal "IN3")
		(16 "In7.Cu" signal "GND3")
		(18 "In8.Cu" signal "VCC")
		(20 "In9.Cu" signal "VCC1")
		(22 "In10.Cu" signal "GND4")
		(24 "In11.Cu" signal "IN4")
		(26 "In12.Cu" signal "GND5")
		(28 "In13.Cu" signal "IN5")
		(30 "In14.Cu" signal "GND6")
		(32 "In15.Cu" signal "IN6")
		(34 "In16.Cu" signal "GND7")
		(2 "B.Cu" signal "BOTTOM")
		(9 "F.Adhes" user "F.Adhesive")
		(11 "B.Adhes" user "B.Adhesive")
		(13 "F.Paste" user "Package Geometry/Pastemask Top")
		(15 "B.Paste" user "Package Geometry/Pastemask Bottom")
		(5 "F.SilkS" user "Ref Des/Silkscreen Top")
		(7 "B.SilkS" user "Ref Des/Silkscreen Bottom")
		(1 "F.Mask" user "Board Geometry/Soldermask Top")
		(3 "B.Mask" user "Board Geometry/Soldermask Bottom")
		(17 "Dwgs.User" user "User.Drawings")
		(19 "Cmts.User" user "User.Comments")
		(21 "Eco1.User" user "User.Eco1")
		(23 "Eco2.User" user "User.Eco2")
		(25 "Edge.Cuts" user "Board Geometry/Outline")
		(27 "Margin" user)
		(31 "F.CrtYd" user "Package Geometry/Place Bound Top")
		(29 "B.CrtYd" user "Package Geometry/Place Bound Bottom")
		(35 "F.Fab" user "Ref Des/Assembly Top")
		(33 "B.Fab" user "Ref Des/Assembly Bottom")
	)
	(footprint ""
		(layer "B.Cu")
		(at 303.472342 -149.533356 180)
		(property "Reference" "C538"
			(at 0 0 0)
			(layer "B.SilkS")
			(hide yes)
			(effects
				(font
					(size 1.27 1.27)
				)
				(justify mirror)
			)
		)
		(property "Value" ""
			(at 0 0 0)
			(layer "B.Fab")
			(effects
				(font
					(size 1.27 1.27)
				)
				(justify mirror)
			)
		)
		(duplicate_pad_numbers_are_jumpers no)
		(fp_line
			(start 0.7874 0.4064)
			(end 0.7874 -0.4064)
			(stroke
				(width 0.1524)
				(type default)
			)
			(layer "B.SilkS")
		)
		(fp_line
			(start 0.7874 -0.4064)
			(end -0.7874 -0.4064)
			(stroke
				(width 0.1524)
				(type default)
			)
			(layer "B.SilkS")
		)
		(fp_line
			(start -0.7874 0.4064)
			(end 0.7874 0.4064)
			(stroke
				(width 0.1524)
				(type default)
			)
			(layer "B.SilkS")
		)
		(fp_line
			(start -0.7874 -0.4064)
			(end -0.7874 0.4064)
			(stroke
				(width 0.1524)
				(type default)
			)
			(layer "B.SilkS")
		)
		(fp_line
			(start 0.67945 0.3048)
			(end 0.67945 -0.305054)
			(stroke
				(width 0.1)
				(type default)
			)
			(layer "B.Fab")
		)
		(fp_line
			(start 0.67945 -0.305054)
			(end 0.12065 -0.305054)
			(stroke
				(width 0.1)
				(type default)
			)
			(layer "B.Fab")
		)
		(fp_line
			(start 0.12065 0.3048)
			(end 0.67945 0.3048)
			(stroke
				(width 0.1)
				(type default)
			)
			(layer "B.Fab")
		)
		(fp_line
			(start 0.12065 0.2794)
			(end 0.12065 0.3048)
			(stroke
				(width 0.1)
				(type default)
			)
			(layer "B.Fab")
		)
		(fp_line
			(start 0.12065 -0.2794)
			(end -0.12065 -0.2794)
			(stroke
				(width 0.1)
				(type default)
			)
			(layer "B.Fab")
		)
		(fp_line
			(start 0.12065 -0.305054)
			(end 0.12065 -0.2794)
			(stroke
				(width 0.1)
				(type default)
			)
			(layer "B.Fab")
		)
		(fp_line
			(start -0.120396 0.3048)
			(end -0.120396 0.2794)
			(stroke
				(width 0.1)
				(type default)
			)
			(layer "B.Fab")
		)
		(fp_line
			(start -0.120396 0.2794)
			(end 0.12065 0.2794)
			(stroke
				(width 0.1)
				(type default)
			)
			(layer "B.Fab")
		)
		(fp_line
			(start -0.12065 -0.2794)
			(end -0.12065 -0.3048)
			(stroke
				(width 0.1)
				(type default)
			)
			(layer "B.Fab")
		)
		(fp_line
			(start -0.12065 -0.3048)
			(end -0.67945 -0.3048)
			(stroke
				(width 0.1)
				(type default)
			)
			(layer "B.Fab")
		)
		(fp_line
			(start -0.67945 0.3048)
			(end -0.120396 0.3048)
			(stroke
				(width 0.1)
				(type default)
			)
			(layer "B.Fab")
		)
		(fp_line
			(start -0.67945 -0.3048)
			(end -0.67945 0.3048)
			(stroke
				(width 0.1)
				(type default)
			)
			(layer "B.Fab")
		)
		(pad "1" smd circle
			(at 0.40005 0)
			(size 0 0)
			(layers "B.Cu" "B.Mask" "B.Paste")
			(net "P3V3_AUX")
		)
		(pad "2" smd circle
			(at -0.40005 0)
			(size 0 0)
			(layers "B.Cu" "B.Mask" "B.Paste")
			(net "GND")
		)
	)
	(footprint ""
		(layer "B.Cu")
		(at 305.470814 -258.379976 -90)
		(property "Reference" "C521"
			(at 0 0 90)
			(layer "B.SilkS")
			(hide yes)
			(effects
				(font
					(size 1.27 1.27)
				)
				(justify mirror)
			)
		)
		(property "Value" ""
			(at 0 0 90)
			(layer "B.Fab")
			(effects
				(font
					(size 1.27 1.27)
				)
				(justify mirror)
			)
		)
		(duplicate_pad_numbers_are_jumpers no)
		(fp_line
			(start -1.524 0.762)
			(end 1.524 0.762)
			(stroke
				(width 0.1524)
				(type default)
			)
			(layer "B.SilkS")
		)
		(fp_line
			(start 1.524 0.762)
			(end 1.524 -0.762)
			(stroke
				(width 0.1524)
				(type default)
			)
			(layer "B.SilkS")
		)
		(fp_line
			(start -1.524 -0.762)
			(end -1.524 0.762)
			(stroke
				(width 0.1524)
				(type default)
			)
			(layer "B.SilkS")
		)
		(fp_line
			(start 1.524 -0.762)
			(end -1.524 -0.762)
			(stroke
				(width 0.1524)
				(type default)
			)
			(layer "B.SilkS")
		)
		(fp_line
			(start -1.1049 0.724916)
			(end -1.1049 -0.724916)
			(stroke
				(width 0.1)
				(type default)
			)
			(layer "B.Fab")
		)
		(fp_line
			(start 1.1049 0.724916)
			(end -1.1049 0.724916)
			(stroke
				(width 0.1)
				(type default)
			)
			(layer "B.Fab")
		)
		(fp_line
			(start -1.1049 -0.724916)
			(end 1.1049 -0.724916)
			(stroke
				(width 0.1)
				(type default)
			)
			(layer "B.Fab")
		)
		(fp_line
			(start 1.1049 -0.724916)
			(end 1.1049 0.724916)
			(stroke
				(width 0.1)
				(type default)
			)
			(layer "B.Fab")
		)
		(pad "1" smd rect
			(at 0.889 0 270)
			(size 1.016 1.27)
			(layers "B.Cu" "B.Mask" "B.Paste")
			(net "PVCCFA_EHV_FIVRA_CPU0")
		)
		(pad "2" smd rect
			(at -0.889 0 270)
			(size 1.016 1.27)
			(layers "B.Cu" "B.Mask" "B.Paste")
			(net "GND")
		)
	)
	(footprint ""
		(layer "B.Cu")
		(at 181.755542 -111.375444)
		(property "Reference" "C1138"
			(at 0 0 0)
			(layer "B.SilkS")
			(hide yes)
			(effects
				(font
					(size 1.27 1.27)
				)
				(justify mirror)
			)
		)
		(property "Value" ""
			(at 0 0 0)
			(layer "B.Fab")
			(effects
				(font
					(size 1.27 1.27)
				)
				(justify mirror)
			)
		)
		(duplicate_pad_numbers_are_jumpers no)
		(fp_line
			(start -0.69215 -0.2921)
			(end -0.69215 0.2921)
			(stroke
				(width 0.1524)
				(type default)
			)
			(layer "B.SilkS")
		)
		(fp_line
			(start -0.69215 0.2921)
			(end 0.69215 0.2921)
			(stroke
				(width 0.1524)
				(type default)
			)
			(layer "B.SilkS")
		)
		(fp_line
			(start 0.69215 -0.2921)
			(end -0.69215 -0.2921)
			(stroke
				(width 0.1524)
				(type default)
			)
			(layer "B.SilkS")
		)
		(fp_line
			(start 0.69215 0.2921)
			(end 0.69215 -0.2921)
			(stroke
				(width 0.1524)
				(type default)
			)
			(layer "B.SilkS")
		)
		(fp_line
			(start -0.51435 -0.2794)
			(end -0.51435 0.2794)
			(stroke
				(width 0.1)
				(type default)
			)
			(layer "B.Fab")
		)
		(fp_line
			(start -0.51435 0.2794)
			(end 0.51435 0.2794)
			(stroke
				(width 0.1)
				(type default)
			)
			(layer "B.Fab")
		)
		(fp_line
			(start 0.51435 -0.2794)
			(end -0.51435 -0.2794)
			(stroke
				(width 0.1)
				(type default)
			)
			(layer "B.Fab")
		)
		(fp_line
			(start 0.51435 0.2794)
			(end 0.51435 -0.2794)
			(stroke
				(width 0.1)
				(type default)
			)
			(layer "B.Fab")
		)
		(pad "1" smd circle
			(at 0.40005 0 180)
			(size 0 0)
			(layers "B.Cu" "B.Mask" "B.Paste")
			(net "P3V3_AUX_FPGA_VCCIO2")
		)
		(pad "2" smd circle
			(at -0.40005 0 180)
			(size 0 0)
			(layers "B.Cu" "B.Mask" "B.Paste")
			(net "GND")
		)
		(zone
			(layer "B.Cu")
			(hatch none 0.5)
			(connect_pads
				(clearance 0)
			)
			(min_thickness 0.25)
			(keepout
				(tracks not_allowed)
				(vias allowed)
				(pads allowed)
				(copperpour not_allowed)
				(footprints allowed)
			)
			(placement
				(enabled no)
				(sheetname "")
			)
			(fill
				(thermal_gap 0.5)
				(thermal_bridge_width 0.5)
				(island_removal_mode 0)
			)
			(polygon
				(pts
					(xy 181.946042 -111.287814) (xy 181.854602 -111.229648) (xy 181.655212 -111.229648) (xy 181.565042 -111.287814)
					(xy 181.565042 -111.463074) (xy 181.655212 -111.521494) (xy 181.854602 -111.521494) (xy 181.946042 -111.463328)
				)
			)
		)
	)
	(footprint ""
		(layer "B.Cu")
		(at 461.445356 -321.549776 -90)
		(property "Reference" "C46"
			(at 0 0 90)
			(layer "B.SilkS")
			(hide yes)
			(effects
				(font
					(size 1.27 1.27)
				)
				(justify mirror)
			)
		)
		(property "Value" ""
			(at 0 0 90)
			(layer "B.Fab")
			(effects
				(font
					(size 1.27 1.27)
				)
				(justify mirror)
			)
		)
		(duplicate_pad_numbers_are_jumpers no)
		(fp_line
			(start -1.524 0.762)
			(end 1.524 0.762)
			(stroke
				(width 0.1524)
				(type default)
			)
			(layer "B.SilkS")
		)
		(fp_line
			(start 1.524 0.762)
			(end 1.524 -0.762)
			(stroke
				(width 0.1524)
				(type default)
			)
			(layer "B.SilkS")
		)
		(fp_line
			(start -1.524 -0.762)
			(end -1.524 0.762)
			(stroke
				(width 0.1524)
				(type default)
			)
			(layer "B.SilkS")
		)
		(fp_line
			(start 1.524 -0.762)
			(end -1.524 -0.762)
			(stroke
				(width 0.1524)
				(type default)
			)
			(layer "B.SilkS")
		)
		(fp_line
			(start -1.1049 0.724916)
			(end -1.1049 -0.724916)
			(stroke
				(width 0.1)
				(type default)
			)
			(layer "B.Fab")
		)
		(fp_line
			(start 1.1049 0.724916)
			(end -1.1049 0.724916)
			(stroke
				(width 0.1)
				(type default)
			)
			(layer "B.Fab")
		)
		(fp_line
			(start -1.1049 -0.724916)
			(end 1.1049 -0.724916)
			(stroke
				(width 0.1)
				(type default)
			)
			(layer "B.Fab")
		)
		(fp_line
			(start 1.1049 -0.724916)
			(end 1.1049 0.724916)
			(stroke
				(width 0.1)
				(type default)
			)
			(layer "B.Fab")
		)
		(pad "1" smd rect
			(at 0.889 0 270)
			(size 1.016 1.27)
			(layers "B.Cu" "B.Mask" "B.Paste")
			(net "P12V_S3_AUX_CPU0_NVDIMM")
		)
		(pad "2" smd rect
			(at -0.889 0 270)
			(size 1.016 1.27)
			(layers "B.Cu" "B.Mask" "B.Paste")
			(net "GND")
		)
	)
	(footprint ""
		(layer "B.Cu")
		(at 245.8212 -102.112318 180)
		(property "Reference" "R1958"
			(at 0 0 0)
			(layer "B.SilkS")
			(hide yes)
			(effects
				(font
					(size 1.27 1.27)
				)
				(justify mirror)
			)
		)
		(property "Value" ""
			(at 0 0 0)
			(layer "B.Fab")
			(effects
				(font
					(size 1.27 1.27)
				)
				(justify mirror)
			)
		)
		(duplicate_pad_numbers_are_jumpers no)
		(fp_line
			(start 0.7874 0.4064)
			(end 0.7874 -0.4064)
			(stroke
				(width 0.1524)
				(type default)
			)
			(layer "B.SilkS")
		)
		(fp_line
			(start 0.7874 -0.4064)
			(end -0.7874 -0.4064)
			(stroke
				(width 0.1524)
				(type default)
			)
			(layer "B.SilkS")
		)
		(fp_line
			(start -0.7874 0.4064)
			(end 0.7874 0.4064)
			(stroke
				(width 0.1524)
				(type default)
			)
			(layer "B.SilkS")
		)
		(fp_line
			(start -0.7874 -0.4064)
			(end -0.7874 0.4064)
			(stroke
				(width 0.1524)
				(type default)
			)
			(layer "B.SilkS")
		)
		(fp_line
			(start 0.67945 0.3048)
			(end 0.67945 -0.305054)
			(stroke
				(width 0.1)
				(type default)
			)
			(layer "B.Fab")
		)
		(fp_line
			(start 0.67945 -0.305054)
			(end 0.12065 -0.305054)
			(stroke
				(width 0.1)
				(type default)
			)
			(layer "B.Fab")
		)
		(fp_line
			(start 0.12065 0.3048)
			(end 0.67945 0.3048)
			(stroke
				(width 0.1)
				(type default)
			)
			(layer "B.Fab")
		)
		(fp_line
			(start 0.12065 0.2794)
			(end 0.12065 0.3048)
			(stroke
				(width 0.1)
				(type default)
			)
			(layer "B.Fab")
		)
		(fp_line
			(start 0.12065 -0.2794)
			(end -0.12065 -0.2794)
			(stroke
				(width 0.1)
				(type default)
			)
			(layer "B.Fab")
		)
		(fp_line
			(start 0.12065 -0.305054)
			(end 0.12065 -0.2794)
			(stroke
				(width 0.1)
				(type default)
			)
			(layer "B.Fab")
		)
		(fp_line
			(start -0.120396 0.3048)
			(end -0.120396 0.2794)
			(stroke
				(width 0.1)
				(type default)
			)
			(layer "B.Fab")
		)
		(fp_line
			(start -0.120396 0.2794)
			(end 0.12065 0.2794)
			(stroke
				(width 0.1)
				(type default)
			)
			(layer "B.Fab")
		)
		(fp_line
			(start -0.12065 -0.2794)
			(end -0.12065 -0.3048)
			(stroke
				(width 0.1)
				(type default)
			)
			(layer "B.Fab")
		)
		(fp_line
			(start -0.12065 -0.3048)
			(end -0.67945 -0.3048)
			(stroke
				(width 0.1)
				(type default)
			)
			(layer "B.Fab")
		)
		(fp_line
			(start -0.67945 0.3048)
			(end -0.120396 0.3048)
			(stroke
				(width 0.1)
				(type default)
			)
			(layer "B.Fab")
		)
		(fp_line
			(start -0.67945 -0.3048)
			(end -0.67945 0.3048)
			(stroke
				(width 0.1)
				(type default)
			)
			(layer "B.Fab")
		)
		(pad "1" smd circle
			(at 0.40005 0)
			(size 0 0)
			(layers "B.Cu" "B.Mask" "B.Paste")
			(net "P3V3_AUX")
		)
		(pad "2" smd circle
			(at -0.40005 0)
			(size 0 0)
			(layers "B.Cu" "B.Mask" "B.Paste")
			(net "PU_CLK_PFT_LOST_N")
		)
	)
	(footprint ""
		(layer "B.Cu")
		(at 173.22292 -13.762228 90)
		(property "Reference" "R2425"
			(at 0 0 90)
			(layer "B.SilkS")
			(hide yes)
			(effects
				(font
					(size 1.27 1.27)
				)
				(justify mirror)
			)
		)
		(property "Value" ""
			(at 0 0 90)
			(layer "B.Fab")
			(effects
				(font
					(size 1.27 1.27)
				)
				(justify mirror)
			)
		)
		(duplicate_pad_numbers_are_jumpers no)
		(fp_line
			(start 0.7874 -0.4064)
			(end -0.7874 -0.4064)
			(stroke
				(width 0.1524)
				(type default)
			)
			(layer "B.SilkS")
		)
		(fp_line
			(start -0.7874 -0.4064)
			(end -0.7874 0.4064)
			(stroke
				(width 0.1524)
				(type default)
			)
			(layer "B.SilkS")
		)
		(fp_line
			(start 0.7874 0.4064)
			(end 0.7874 -0.4064)
			(stroke
				(width 0.1524)
				(type default)
			)
			(layer "B.SilkS")
		)
		(fp_line
			(start -0.7874 0.4064)
			(end 0.7874 0.4064)
			(stroke
				(width 0.1524)
				(type default)
			)
			(layer "B.SilkS")
		)
		(fp_line
			(start 0.67945 -0.305054)
			(end 0.12065 -0.305054)
			(stroke
				(width 0.1)
				(type default)
			)
			(layer "B.Fab")
		)
		(fp_line
			(start 0.12065 -0.305054)
			(end 0.12065 -0.2794)
			(stroke
				(width 0.1)
				(type default)
			)
			(layer "B.Fab")
		)
		(fp_line
			(start -0.12065 -0.3048)
			(end -0.67945 -0.3048)
			(stroke
				(width 0.1)
				(type default)
			)
			(layer "B.Fab")
		)
		(fp_line
			(start -0.67945 -0.3048)
			(end -0.67945 0.3048)
			(stroke
				(width 0.1)
				(type default)
			)
			(layer "B.Fab")
		)
		(fp_line
			(start 0.12065 -0.2794)
			(end -0.12065 -0.2794)
			(stroke
				(width 0.1)
				(type default)
			)
			(layer "B.Fab")
		)
		(fp_line
			(start -0.12065 -0.2794)
			(end -0.12065 -0.3048)
			(stroke
				(width 0.1)
				(type default)
			)
			(layer "B.Fab")
		)
		(fp_line
			(start 0.12065 0.2794)
			(end 0.12065 0.3048)
			(stroke
				(width 0.1)
				(type default)
			)
			(layer "B.Fab")
		)
		(fp_line
			(start -0.120396 0.2794)
			(end 0.12065 0.2794)
			(stroke
				(width 0.1)
				(type default)
			)
			(layer "B.Fab")
		)
		(fp_line
			(start 0.67945 0.3048)
			(end 0.67945 -0.305054)
			(stroke
				(width 0.1)
				(type default)
			)
			(layer "B.Fab")
		)
		(fp_line
			(start 0.12065 0.3048)
			(end 0.67945 0.3048)
			(stroke
				(width 0.1)
				(type default)
			)
			(layer "B.Fab")
		)
		(fp_line
			(start -0.120396 0.3048)
			(end -0.120396 0.2794)
			(stroke
				(width 0.1)
				(type default)
			)
			(layer "B.Fab")
		)
		(fp_line
			(start -0.67945 0.3048)
			(end -0.120396 0.3048)
			(stroke
				(width 0.1)
				(type default)
			)
			(layer "B.Fab")
		)
		(pad "1" smd circle
			(at 0.40005 0 270)
			(size 0 0)
			(layers "B.Cu" "B.Mask" "B.Paste")
			(net "SMB_OCP_V3_2_3V3AUX_SCL")
		)
		(pad "2" smd circle
			(at -0.40005 0 270)
			(size 0 0)
			(layers "B.Cu" "B.Mask" "B.Paste")
			(net "SMB_OCP_V3_2_3V3AUX_SCL_R0")
		)
	)
	(footprint ""
		(layer "B.Cu")
		(at 288.376106 -313.866784 90)
		(property "Reference" "R2499"
			(at 0 0 90)
			(layer "B.SilkS")
			(hide yes)
			(effects
				(font
					(size 1.27 1.27)
				)
				(justify mirror)
			)
		)
		(property "Value" ""
			(at 0 0 90)
			(layer "B.Fab")
			(effects
				(font
					(size 1.27 1.27)
				)
				(justify mirror)
			)
		)
		(duplicate_pad_numbers_are_jumpers no)
		(fp_line
			(start 0.7874 -0.4064)
			(end -0.7874 -0.4064)
			(stroke
				(width 0.1524)
				(type default)
			)
			(layer "B.SilkS")
		)
		(fp_line
			(start -0.7874 -0.4064)
			(end -0.7874 0.4064)
			(stroke
				(width 0.1524)
				(type default)
			)
			(layer "B.SilkS")
		)
		(fp_line
			(start 0.7874 0.4064)
			(end 0.7874 -0.4064)
			(stroke
				(width 0.1524)
				(type default)
			)
			(layer "B.SilkS")
		)
		(fp_line
			(start -0.7874 0.4064)
			(end 0.7874 0.4064)
			(stroke
				(width 0.1524)
				(type default)
			)
			(layer "B.SilkS")
		)
		(fp_line
			(start 0.67945 -0.305054)
			(end 0.12065 -0.305054)
			(stroke
				(width 0.1)
				(type default)
			)
			(layer "B.Fab")
		)
		(fp_line
			(start 0.12065 -0.305054)
			(end 0.12065 -0.2794)
			(stroke
				(width 0.1)
				(type default)
			)
			(layer "B.Fab")
		)
		(fp_line
			(start -0.12065 -0.3048)
			(end -0.67945 -0.3048)
			(stroke
				(width 0.1)
				(type default)
			)
			(layer "B.Fab")
		)
		(fp_line
			(start -0.67945 -0.3048)
			(end -0.67945 0.3048)
			(stroke
				(width 0.1)
				(type default)
			)
			(layer "B.Fab")
		)
		(fp_line
			(start 0.12065 -0.2794)
			(end -0.12065 -0.2794)
			(stroke
				(width 0.1)
				(type default)
			)
			(layer "B.Fab")
		)
		(fp_line
			(start -0.12065 -0.2794)
			(end -0.12065 -0.3048)
			(stroke
				(width 0.1)
				(type default)
			)
			(layer "B.Fab")
		)
		(fp_line
			(start 0.12065 0.2794)
			(end 0.12065 0.3048)
			(stroke
				(width 0.1)
				(type default)
			)
			(layer "B.Fab")
		)
		(fp_line
			(start -0.120396 0.2794)
			(end 0.12065 0.2794)
			(stroke
				(width 0.1)
				(type default)
			)
			(layer "B.Fab")
		)
		(fp_line
			(start 0.67945 0.3048)
			(end 0.67945 -0.305054)
			(stroke
				(width 0.1)
				(type default)
			)
			(layer "B.Fab")
		)
		(fp_line
			(start 0.12065 0.3048)
			(end 0.67945 0.3048)
			(stroke
				(width 0.1)
				(type default)
			)
			(layer "B.Fab")
		)
		(fp_line
			(start -0.120396 0.3048)
			(end -0.120396 0.2794)
			(stroke
				(width 0.1)
				(type default)
			)
			(layer "B.Fab")
		)
		(fp_line
			(start -0.67945 0.3048)
			(end -0.120396 0.3048)
			(stroke
				(width 0.1)
				(type default)
			)
			(layer "B.Fab")
		)
		(pad "1" smd circle
			(at 0.40005 0 270)
			(size 0 0)
			(layers "B.Cu" "B.Mask" "B.Paste")
			(net "PWRGD_FAIL_CPU0_CD_R1")
		)
		(pad "2" smd circle
			(at -0.40005 0 270)
			(size 0 0)
			(layers "B.Cu" "B.Mask" "B.Paste")
			(net "PWRGD_FAIL_CPU0_CD_R")
		)
	)
)
